#ISCELL
  mstr_misc dns *
  *
#ISCELL
  mstr_symbols cad_note *
  *
#ISCELL
  mstr_symbols intel_corp_bpage *
  *
#CELL
  mstr_ttl ttl2g14 *
  page175_i10
#CELL
  dev_discrete cap_a *
  page175_i11
#ISCELL
  mstr_symbols gnd *
  page175_i12
#CELL
  mstr_discrete res *
  page175_i13
#ISCELL
  mstr_standard offpage *
  page175_i14
#CELL
  mstr_ttl ttl2g14 *
  page175_i15
#CELL
  mstr_ttl ttl2g14 *
  page175_i18
#CELL
  dev_discrete cap_a *
  page175_i19
#ISCELL
  mstr_symbols gnd *
  page175_i20
#ISCELL
  mstr_symbols p3v3_stby *
  page175_i21
#CELL
  mstr_discrete res *
  page175_i22
#CELL
  mstr_discrete res *
  page175_i24
#ISCELL
  mstr_symbols gnd *
  page175_i27
#ISCELL
  mstr_standard offpage *
  page175_i28
#ISCELL
  mstr_symbols gnd *
  page175_i3
#CELL
  mstr_discrete res *
  page175_i35
#ISCELL
  mstr_standard offpage *
  page175_i36
#CELL
  dev_discrete cap_a *
  page175_i37
#CELL
  dev_discrete cap_a *
  page175_i38
#CELL
  mstr_discrete res *
  page175_i4
#CELL
  dev_discrete cap_a *
  page175_i40
#ISCELL
  mstr_symbols gnd *
  page175_i41
#ISCELL
  mstr_symbols gnd *
  page175_i42
#ISCELL
  mstr_symbols p3v3_stby *
  page175_i43
#ISCELL
  mstr_symbols p3v3_stby *
  page175_i44
#CELL
  mstr_discrete res *
  page175_i45
#CELL
  mstr_discrete fet_n *
  page175_i49
#CELL
  mstr_discrete res *
  page175_i5
#CELL
  mstr_discrete led *
  page175_i50
#ISCELL
  mstr_standard offpage *
  page175_i52
#ISCELL
  mstr_symbols gnd *
  page175_i54
#CELL
  mstr_ttl ttl1g86 *
  page175_i57
#CELL
  mstr_discrete res *
  page175_i58
#ISCELL
  mstr_symbols p5v_stby *
  page175_i59
#ISCELL
  mstr_symbols p3v3_stby *
  page175_i6
#ISCELL
  mstr_standard offpage *
  page175_i61
#ISCELL
  mstr_standard offpage *
  page175_i62
#CELL
  mstr_discrete res *
  page175_i63
#CELL
  dev_discrete cap_a *
  page175_i64
#ISCELL
  mstr_symbols gnd *
  page175_i66
#CELL
  mstr_discrete led *
  page175_i67
#ISCELL
  mstr_symbols p3v3_stby *
  page175_i70
#ISCELL
  mstr_symbols gnd *
  page175_i71
#CELL
  mstr_misc switch_d37771002 *
  page175_i78
#CELL
  mstr_misc sw_h67881001 *
  page175_i84
#ISCELL
  mstr_symbols p3v3_stby *
  page175_i85
#ISCELL
  mstr_symbols p5v_stby *
  page175_i86
#ISCELL
  mstr_standard offpage *
  page175_i87
#ISCELL
  mstr_standard offpage *
  page175_i88
#CELL
  w_hdl 0r2j-l-gp *
  page175_i89
#CELL
  mstr_ttl ttl2g14 *
  page175_i9
